# TIMECARD (Time Appliance Project (Time Card)) — schematic netlist excerpt (pin names and nets, part order shuffled) for the footprints in the layout excerpt that follows; sources: Cadence DE-HDL packaged netlist, KiCad conversion of R4006-B0001-02_R01.brd

R67  RESISTOR  33OHM 1%  pkg SMC_0402R_H016  page 18 : \1\ = SHT3X_I2C_SCL ; \2\ = R_SHT3X_I2C_SCL
SP31  SOLDER_PREFORM  pkg 0201_SOLDER_PREFORM_4MIL  page 34 : \1\ = NC ; \2\ = NC
TP10  TP_PIONT  pkg TP010CT020B030_PTH  page 24 : \1\ = UNNAMED_524_FT4232HLREELQFP64_5
C238  CAPACITOR  22UF 10V 20%  pkg SMC_0805R_H057  page 31 : \1\ = XP3R3V_FPGA ; \2\ = SG

(kicad_pcb
	(version 20260206)
	(generator "pcbnew")
	(generator_version "10.0")
	(general
		(thickness 1.6)
		(legacy_teardrops no)
	)
	(paper "A4")
	(title_block
		(title "timecard-production-celestica-r4006 — R4006-B0001-02_R01.brd")
		(comment 1 "Time Appliance Project (Time Card) / footprints 578-581 of 1113")
	)
	(layers
		(0 "F.Cu" signal "TOP")
		(4 "In1.Cu" signal "L02_GND1")
		(6 "In2.Cu" signal "L03_SIG1")
		(8 "In3.Cu" signal "L04_GND2")
		(10 "In4.Cu" signal "L05_VCC1")
		(12 "In5.Cu" signal "L06_VCC2")
		(14 "In6.Cu" signal "L07_GND3")
		(16 "In7.Cu" signal "L08_SIG2")
		(18 "In8.Cu" signal "L09_GND4")
		(2 "B.Cu" signal "BOTTOM")
		(9 "F.Adhes" user "F.Adhesive")
		(11 "B.Adhes" user "B.Adhesive")
		(13 "F.Paste" user "Package Geometry/Pastemask Top")
		(15 "B.Paste" user "Package Geometry/Pastemask Bottom")
		(5 "F.SilkS" user "Ref Des/Silkscreen Top")
		(7 "B.SilkS" user "Ref Des/Silkscreen Bottom")
		(1 "F.Mask" user "Board Geometry/Soldermask Top")
		(3 "B.Mask" user "Board Geometry/Soldermask Bottom")
		(17 "Dwgs.User" user "User.Drawings")
		(19 "Cmts.User" user "User.Comments")
		(21 "Eco1.User" user "User.Eco1")
		(23 "Eco2.User" user "User.Eco2")
		(25 "Edge.Cuts" user "Board Geometry/Outline")
		(27 "Margin" user)
		(31 "F.CrtYd" user "Package Geometry/Place Bound Top")
		(29 "B.CrtYd" user "Package Geometry/Place Bound Bottom")
		(35 "F.Fab" user "Ref Des/Assembly Top")
		(33 "B.Fab" user "Ref Des/Assembly Bottom")
	)
	(footprint ""
		(layer "F.Cu")
		(at 24.13 -74.041 90)
		(property "Reference" "TP10"
			(at 0 0 90)
			(layer "F.SilkS")
			(hide yes)
			(effects
				(font
					(size 1.27 1.27)
				)
			)
		)
		(property "Value" ""
			(at 0 0 90)
			(layer "F.Fab")
			(effects
				(font
					(size 1.27 1.27)
				)
			)
		)
		(property "Device Type" "TP_PIONT-TP010CT020B030_PTH-TPA"
			(at -1.341882 0.996696 90)
			(unlocked yes)
			(layer "F.Fab")
			(hide yes)
			(effects
				(font
					(size 0.7874 0.5842)
					(thickness 0.1524)
				)
				(justify left)
			)
		)
		(duplicate_pad_numbers_are_jumpers no)
		(fp_poly
			(pts
				(arc
					(start 0 0.889)
					(mid 0 -0.889)
					(end 0 0.889)
				)
			)
			(stroke
				(width 0)
				(type default)
			)
			(fill no)
			(layer "B.CrtYd")
		)
		(fp_poly
			(pts
				(arc
					(start 0 0.889)
					(mid 0 -0.889)
					(end 0 0.889)
				)
			)
			(stroke
				(width 0)
				(type default)
			)
			(fill no)
			(layer "F.CrtYd")
		)
		(pad "1" thru_hole circle
			(at 0 0 90)
			(size 0.508 0.508)
			(drill 0.254)
			(layers "*.Cu" "*.Mask")
			(remove_unused_layers no)
			(net "UNNAMED_524_FT4232HLREELQFP64_5")
			(clearance 0.1016)
			(padstack
				(mode front_inner_back)
				(layer "Inner"
					(shape circle)
					(size 0.508 0.508)
					(clearance 0.1016)
				)
				(layer "B.Cu"
					(shape circle)
					(size 0.762 0.762)
					(clearance -0.0254)
				)
			)
		)
	)
	(footprint ""
		(layer "F.Cu")
		(at 105.8418 -74.5744 180)
		(property "Reference" "C238"
			(at -0.3302 -5.00507 0)
			(unlocked yes)
			(layer "F.SilkS")
			(effects
				(font
					(size 0.7874 0.5842)
					(thickness 0.1524)
				)
			)
		)
		(property "Value" "VAL*"
			(at 0.0762 3.134106 180)
			(unlocked yes)
			(layer "F.Fab")
			(hide yes)
			(effects
				(font
					(size 0.7874 0.5842)
					(thickness 0.1524)
				)
			)
		)
		(property "Device Type" "CAPACITOR-G107-0F226-CM,22UF,2A"
			(at 0.0508 2.194306 180)
			(unlocked yes)
			(layer "F.Fab")
			(hide yes)
			(effects
				(font
					(size 0.7874 0.5842)
					(thickness 0.1524)
				)
			)
		)
		(property "User Part Number" "PARTNUM*"
			(at 0.1016 5.013706 180)
			(unlocked yes)
			(layer "Cmts.User")
			(hide yes)
			(effects
				(font
					(size 0.7874 0.5842)
					(thickness 0.1524)
				)
			)
		)
		(property "Tolerance" "TOL*"
			(at 0.0762 4.048506 180)
			(unlocked yes)
			(layer "Cmts.User")
			(hide yes)
			(effects
				(font
					(size 0.7874 0.5842)
					(thickness 0.1524)
				)
			)
		)
		(duplicate_pad_numbers_are_jumpers no)
		(fp_line
			(start 1.5748 0.9398)
			(end 1.5748 -0.9398)
			(stroke
				(width 0.1)
				(type default)
			)
			(layer "F.SilkS")
		)
		(fp_line
			(start 1.5748 -0.9398)
			(end -1.5748 -0.9398)
			(stroke
				(width 0.1)
				(type default)
			)
			(layer "F.SilkS")
		)
		(fp_line
			(start -1.5748 0.9398)
			(end 1.5748 0.9398)
			(stroke
				(width 0.1)
				(type default)
			)
			(layer "F.SilkS")
		)
		(fp_line
			(start -1.5748 -0.9398)
			(end -1.5748 0.9398)
			(stroke
				(width 0.1)
				(type default)
			)
			(layer "F.SilkS")
		)
		(fp_rect
			(start -1.5748 0.9398)
			(end 1.5748 -0.9398)
			(stroke
				(width 0)
				(type default)
			)
			(fill no)
			(layer "F.CrtYd")
		)
		(fp_line
			(start 1.016 0.635)
			(end 1.016 -0.635)
			(stroke
				(width 0.1)
				(type default)
			)
			(layer "F.Fab")
		)
		(fp_line
			(start 1.016 -0.635)
			(end -1.016 -0.635)
			(stroke
				(width 0.1)
				(type default)
			)
			(layer "F.Fab")
		)
		(fp_line
			(start -1.016 0.635)
			(end 1.016 0.635)
			(stroke
				(width 0.1)
				(type default)
			)
			(layer "F.Fab")
		)
		(fp_line
			(start -1.016 -0.635)
			(end -1.016 0.635)
			(stroke
				(width 0.1)
				(type default)
			)
			(layer "F.Fab")
		)
		(pad "1" smd rect
			(at -0.8382 0 180)
			(size 0.9652 1.3716)
			(layers "F.Cu" "F.Mask" "F.Paste")
			(net "XP3R3V_FPGA")
		)
		(pad "2" smd rect
			(at 0.8382 0 180)
			(size 0.9652 1.3716)
			(layers "F.Cu" "F.Mask" "F.Paste")
			(net "SG")
		)
		(zone
			(layer "F.Cu")
			(hatch none 0.5)
			(connect_pads
				(clearance 0)
			)
			(min_thickness 0.25)
			(keepout
				(tracks allowed)
				(vias not_allowed)
				(pads allowed)
				(copperpour not_allowed)
				(footprints allowed)
			)
			(placement
				(enabled no)
				(sheetname "")
			)
			(fill
				(thermal_gap 0.5)
				(thermal_bridge_width 0.5)
				(island_removal_mode 0)
			)
			(polygon
				(pts
					(xy 106.0704 -75.2094) (xy 105.6132 -75.2094) (xy 105.6132 -73.9394) (xy 106.0704 -73.9394)
				)
			)
		)
	)
	(footprint ""
		(layer "F.Cu")
		(at 154.153108 -49.01311 90)
		(property "Reference" "R67"
			(at 0.00889 2.604262 90)
			(unlocked yes)
			(layer "F.SilkS")
			(effects
				(font
					(size 0.7874 0.5842)
					(thickness 0.1524)
				)
			)
		)
		(property "Value" "VAL*"
			(at 0.02032 2.13233 90)
			(unlocked yes)
			(layer "F.Fab")
			(hide yes)
			(effects
				(font
					(size 0.7874 0.5842)
					(thickness 0.1524)
				)
			)
		)
		(property "Device Type" "RESISTOR-G155-133R0-01,33OHM,1%"
			(at 0.008382 1.210564 90)
			(unlocked yes)
			(layer "F.Fab")
			(hide yes)
			(effects
				(font
					(size 0.7874 0.5842)
					(thickness 0.1524)
				)
			)
		)
		(property "User Part Number" "PARTNUM*"
			(at 0.02032 4.024884 90)
			(unlocked yes)
			(layer "Cmts.User")
			(hide yes)
			(effects
				(font
					(size 0.7874 0.5842)
					(thickness 0.1524)
				)
			)
		)
		(property "Tolerance" "TOL*"
			(at 0.044704 3.05435 90)
			(unlocked yes)
			(layer "Cmts.User")
			(hide yes)
			(effects
				(font
					(size 0.7874 0.5842)
					(thickness 0.1524)
				)
			)
		)
		(duplicate_pad_numbers_are_jumpers no)
		(fp_line
			(start 1.143 -0.5588)
			(end -1.143 -0.5588)
			(stroke
				(width 0.1)
				(type default)
			)
			(layer "F.SilkS")
		)
		(fp_line
			(start -1.143 -0.5588)
			(end -1.143 0.5588)
			(stroke
				(width 0.1)
				(type default)
			)
			(layer "F.SilkS")
		)
		(fp_line
			(start 1.143 0.5588)
			(end 1.143 -0.5588)
			(stroke
				(width 0.1)
				(type default)
			)
			(layer "F.SilkS")
		)
		(fp_line
			(start -1.143 0.5588)
			(end 1.143 0.5588)
			(stroke
				(width 0.1)
				(type default)
			)
			(layer "F.SilkS")
		)
		(fp_rect
			(start 1.143 0.5588)
			(end -1.143 -0.5588)
			(stroke
				(width 0)
				(type default)
			)
			(fill no)
			(layer "F.CrtYd")
		)
		(fp_line
			(start 0.508 -0.3048)
			(end -0.508 -0.3048)
			(stroke
				(width 0.1)
				(type default)
			)
			(layer "F.Fab")
		)
		(fp_line
			(start -0.508 -0.3048)
			(end -0.508 0.3048)
			(stroke
				(width 0.1)
				(type default)
			)
			(layer "F.Fab")
		)
		(fp_line
			(start 0.508 0.3048)
			(end 0.508 -0.3048)
			(stroke
				(width 0.1)
				(type default)
			)
			(layer "F.Fab")
		)
		(fp_line
			(start -0.508 0.3048)
			(end 0.508 0.3048)
			(stroke
				(width 0.1)
				(type default)
			)
			(layer "F.Fab")
		)
		(pad "1" smd rect
			(at -0.5334 0 90)
			(size 0.7112 0.6096)
			(layers "F.Cu" "F.Mask" "F.Paste")
			(net "SHT3X_I2C_SCL")
		)
		(pad "2" smd rect
			(at 0.5334 0 90)
			(size 0.7112 0.6096)
			(layers "F.Cu" "F.Mask" "F.Paste")
			(net "R_SHT3X_I2C_SCL")
		)
		(zone
			(layer "F.Cu")
			(hatch none 0.5)
			(connect_pads
				(clearance 0)
			)
			(min_thickness 0.25)
			(keepout
				(tracks allowed)
				(vias not_allowed)
				(pads allowed)
				(copperpour not_allowed)
				(footprints allowed)
			)
			(placement
				(enabled no)
				(sheetname "")
			)
			(fill
				(thermal_gap 0.5)
				(thermal_bridge_width 0.5)
				(island_removal_mode 0)
			)
			(polygon
				(pts
					(xy 154.457908 -49.08931) (xy 153.848308 -49.08931) (xy 153.848308 -48.93691) (xy 154.457908 -48.93691)
				)
			)
		)
	)
	(footprint ""
		(layer "F.Cu")
		(at 72.136 -128.27)
		(property "Reference" "SP31"
			(at 0 0 0)
			(layer "F.SilkS")
			(hide yes)
			(effects
				(font
					(size 1.27 1.27)
				)
			)
		)
		(property "Value" ""
			(at 0 0 0)
			(layer "F.Fab")
			(effects
				(font
					(size 1.27 1.27)
				)
			)
		)
		(duplicate_pad_numbers_are_jumpers no)
	)
)
